(kicad_pcb
	(version 20260206)
	(generator "pcbnew")
	(generator_version "10.0")
	(general
		(thickness 1.6)
		(legacy_teardrops no)
	)
	(paper "A4")
	(title_block
		(title "01162023_DA0F0TEBIF0_F0T_Expander_BD_F_brd_V02_OCP.brd")
		(comment 1 "Grand Teton / footprints 5898-5903 of 9728")
	)
	(layers
		(0 "F.Cu" signal "TOP")
		(4 "In1.Cu" signal "GND")
		(6 "In2.Cu" signal "VCC")
		(8 "In3.Cu" signal "VCC1")
		(10 "In4.Cu" signal "GND1")
		(12 "In5.Cu" signal "IN1")
		(14 "In6.Cu" signal "GND2")
		(16 "In7.Cu" signal "IN2")
		(18 "In8.Cu" signal "GND3")
		(20 "In9.Cu" signal "IN3")
		(22 "In10.Cu" signal "GND4")
		(24 "In11.Cu" signal "IN4")
		(26 "In12.Cu" signal "GND5")
		(28 "In13.Cu" signal "IN5")
		(30 "In14.Cu" signal "GND6")
		(32 "In15.Cu" signal "IN6")
		(34 "In16.Cu" signal "GND7")
		(2 "B.Cu" signal "BOTTOM")
		(9 "F.Adhes" user "F.Adhesive")
		(11 "B.Adhes" user "B.Adhesive")
		(13 "F.Paste" user "Package Geometry/Pastemask Top")
		(15 "B.Paste" user "Package Geometry/Pastemask Bottom")
		(5 "F.SilkS" user "Ref Des/Silkscreen Top")
		(7 "B.SilkS" user "Ref Des/Silkscreen Bottom")
		(1 "F.Mask" user "Board Geometry/Soldermask Top")
		(3 "B.Mask" user "Board Geometry/Soldermask Bottom")
		(17 "Dwgs.User" user "User.Drawings")
		(19 "Cmts.User" user "User.Comments")
		(21 "Eco1.User" user "User.Eco1")
		(23 "Eco2.User" user "User.Eco2")
		(25 "Edge.Cuts" user "Board Geometry/Outline")
		(27 "Margin" user)
		(31 "F.CrtYd" user "Package Geometry/Place Bound Top")
		(29 "B.CrtYd" user "Package Geometry/Place Bound Bottom")
		(35 "F.Fab" user "Ref Des/Assembly Top")
		(33 "B.Fab" user "Ref Des/Assembly Bottom")
	)
	(footprint ""
		(layer "F.Cu")
		(at 251.938536 -44.341542 90)
		(property "Reference" "C323"
			(at 0 0 90)
			(layer "F.SilkS")
			(hide yes)
			(effects
				(font
					(size 1.27 1.27)
				)
			)
		)
		(property "Value" ""
			(at 0 0 90)
			(layer "F.Fab")
			(effects
				(font
					(size 1.27 1.27)
				)
			)
		)
		(duplicate_pad_numbers_are_jumpers no)
		(fp_line
			(start 0.7874 -0.4064)
			(end 0.7874 0.4064)
			(stroke
				(width 0.1524)
				(type default)
			)
			(layer "F.SilkS")
		)
		(fp_line
			(start -0.7874 -0.4064)
			(end 0.7874 -0.4064)
			(stroke
				(width 0.1524)
				(type default)
			)
			(layer "F.SilkS")
		)
		(fp_line
			(start 0.7874 0.4064)
			(end -0.7874 0.4064)
			(stroke
				(width 0.1524)
				(type default)
			)
			(layer "F.SilkS")
		)
		(fp_line
			(start -0.7874 0.4064)
			(end -0.7874 -0.4064)
			(stroke
				(width 0.1524)
				(type default)
			)
			(layer "F.SilkS")
		)
		(fp_line
			(start -0.12065 -0.305054)
			(end -0.12065 -0.2794)
			(stroke
				(width 0.1)
				(type default)
			)
			(layer "F.Fab")
		)
		(fp_line
			(start -0.67945 -0.305054)
			(end -0.12065 -0.305054)
			(stroke
				(width 0.1)
				(type default)
			)
			(layer "F.Fab")
		)
		(fp_line
			(start 0.67945 -0.3048)
			(end 0.67945 0.3048)
			(stroke
				(width 0.1)
				(type default)
			)
			(layer "F.Fab")
		)
		(fp_line
			(start 0.12065 -0.3048)
			(end 0.67945 -0.3048)
			(stroke
				(width 0.1)
				(type default)
			)
			(layer "F.Fab")
		)
		(fp_line
			(start 0.12065 -0.2794)
			(end 0.12065 -0.3048)
			(stroke
				(width 0.1)
				(type default)
			)
			(layer "F.Fab")
		)
		(fp_line
			(start -0.12065 -0.2794)
			(end 0.12065 -0.2794)
			(stroke
				(width 0.1)
				(type default)
			)
			(layer "F.Fab")
		)
		(fp_line
			(start 0.120396 0.2794)
			(end -0.12065 0.2794)
			(stroke
				(width 0.1)
				(type default)
			)
			(layer "F.Fab")
		)
		(fp_line
			(start -0.12065 0.2794)
			(end -0.12065 0.3048)
			(stroke
				(width 0.1)
				(type default)
			)
			(layer "F.Fab")
		)
		(fp_line
			(start 0.67945 0.3048)
			(end 0.120396 0.3048)
			(stroke
				(width 0.1)
				(type default)
			)
			(layer "F.Fab")
		)
		(fp_line
			(start 0.120396 0.3048)
			(end 0.120396 0.2794)
			(stroke
				(width 0.1)
				(type default)
			)
			(layer "F.Fab")
		)
		(fp_line
			(start -0.12065 0.3048)
			(end -0.67945 0.3048)
			(stroke
				(width 0.1)
				(type default)
			)
			(layer "F.Fab")
		)
		(fp_line
			(start -0.67945 0.3048)
			(end -0.67945 -0.305054)
			(stroke
				(width 0.1)
				(type default)
			)
			(layer "F.Fab")
		)
		(pad "1" smd circle
			(at -0.40005 0 90)
			(size 0 0)
			(layers "F.Cu" "F.Mask" "F.Paste")
			(net "P12V_SSD8_VIN_P")
		)
		(pad "2" smd circle
			(at 0.40005 0 90)
			(size 0 0)
			(layers "F.Cu" "F.Mask" "F.Paste")
			(net "P12V_SSD8_VIN_N")
		)
	)
	(footprint ""
		(layer "F.Cu")
		(at 95.1992 -196.4944 90)
		(property "Reference" "C4443"
			(at 0 0 90)
			(layer "F.SilkS")
			(hide yes)
			(effects
				(font
					(size 1.27 1.27)
				)
			)
		)
		(property "Value" ""
			(at 0 0 90)
			(layer "F.Fab")
			(effects
				(font
					(size 1.27 1.27)
				)
			)
		)
		(duplicate_pad_numbers_are_jumpers no)
		(fp_line
			(start 1.2954 -0.5842)
			(end 1.2954 0.5842)
			(stroke
				(width 0.1524)
				(type default)
			)
			(layer "F.SilkS")
		)
		(fp_line
			(start -1.2954 -0.5842)
			(end 1.2954 -0.5842)
			(stroke
				(width 0.1524)
				(type default)
			)
			(layer "F.SilkS")
		)
		(fp_line
			(start 1.2954 0.5842)
			(end -1.2954 0.5842)
			(stroke
				(width 0.1524)
				(type default)
			)
			(layer "F.SilkS")
		)
		(fp_line
			(start -1.2954 0.5842)
			(end -1.2954 -0.5842)
			(stroke
				(width 0.1524)
				(type default)
			)
			(layer "F.SilkS")
		)
		(fp_line
			(start 0.8636 -0.4572)
			(end 0.8636 -0.4064)
			(stroke
				(width 0.1)
				(type default)
			)
			(layer "F.Fab")
		)
		(fp_line
			(start -0.8636 -0.4572)
			(end 0.8636 -0.4572)
			(stroke
				(width 0.1)
				(type default)
			)
			(layer "F.Fab")
		)
		(fp_line
			(start 1.1938 -0.4064)
			(end 1.1938 0.4064)
			(stroke
				(width 0.1)
				(type default)
			)
			(layer "F.Fab")
		)
		(fp_line
			(start 0.8636 -0.4064)
			(end 1.1938 -0.4064)
			(stroke
				(width 0.1)
				(type default)
			)
			(layer "F.Fab")
		)
		(fp_line
			(start -0.8636 -0.4064)
			(end -0.8636 -0.4572)
			(stroke
				(width 0.1)
				(type default)
			)
			(layer "F.Fab")
		)
		(fp_line
			(start -1.1938 -0.4064)
			(end -0.8636 -0.4064)
			(stroke
				(width 0.1)
				(type default)
			)
			(layer "F.Fab")
		)
		(fp_line
			(start 1.1938 0.4064)
			(end 0.8636 0.4064)
			(stroke
				(width 0.1)
				(type default)
			)
			(layer "F.Fab")
		)
		(fp_line
			(start 0.8636 0.4064)
			(end 0.8636 0.4572)
			(stroke
				(width 0.1)
				(type default)
			)
			(layer "F.Fab")
		)
		(fp_line
			(start -0.8636 0.4064)
			(end -1.1938 0.4064)
			(stroke
				(width 0.1)
				(type default)
			)
			(layer "F.Fab")
		)
		(fp_line
			(start -1.1938 0.4064)
			(end -1.1938 -0.4064)
			(stroke
				(width 0.1)
				(type default)
			)
			(layer "F.Fab")
		)
		(fp_line
			(start 0.8636 0.4572)
			(end -0.8636 0.4572)
			(stroke
				(width 0.1)
				(type default)
			)
			(layer "F.Fab")
		)
		(fp_line
			(start -0.8636 0.4572)
			(end -0.8636 0.4064)
			(stroke
				(width 0.1)
				(type default)
			)
			(layer "F.Fab")
		)
		(pad "1" smd rect
			(at -0.7366 0)
			(size 0.7112 0.8128)
			(layers "F.Cu" "F.Mask" "F.Paste")
			(net "P3V3_AUX")
		)
		(pad "2" smd rect
			(at 0.7366 0)
			(size 0.7112 0.8128)
			(layers "F.Cu" "F.Mask" "F.Paste")
			(net "GND")
		)
	)
	(footprint ""
		(layer "F.Cu")
		(at 147.68957 -63.56223)
		(property "Reference" "Q201"
			(at -0.044196 -2.749042 0)
			(unlocked yes)
			(layer "F.SilkS")
			(effects
				(font
					(size 0.7874 0.5842)
					(thickness 0.1524)
				)
			)
		)
		(property "Value" ""
			(at 0 0 0)
			(layer "F.Fab")
			(effects
				(font
					(size 1.27 1.27)
				)
			)
		)
		(duplicate_pad_numbers_are_jumpers no)
		(fp_line
			(start -1.376172 -1.199896)
			(end -0.508 -1.199896)
			(stroke
				(width 0.1524)
				(type default)
			)
			(layer "F.SilkS")
		)
		(fp_line
			(start -1.376172 1.199896)
			(end -1.376172 -1.199896)
			(stroke
				(width 0.1524)
				(type default)
			)
			(layer "F.SilkS")
		)
		(fp_line
			(start -0.508 -1.199896)
			(end 0 -0.762)
			(stroke
				(width 0.1524)
				(type default)
			)
			(layer "F.SilkS")
		)
		(fp_line
			(start 0 -0.762)
			(end 0.508 -1.199896)
			(stroke
				(width 0.1524)
				(type default)
			)
			(layer "F.SilkS")
		)
		(fp_line
			(start 0.508 -1.199896)
			(end 1.376172 -1.199896)
			(stroke
				(width 0.1524)
				(type default)
			)
			(layer "F.SilkS")
		)
		(fp_line
			(start 1.376172 -1.199896)
			(end 1.376172 1.199896)
			(stroke
				(width 0.1524)
				(type default)
			)
			(layer "F.SilkS")
		)
		(fp_line
			(start 1.376172 1.199896)
			(end -1.376172 1.199896)
			(stroke
				(width 0.1524)
				(type default)
			)
			(layer "F.SilkS")
		)
		(fp_poly
			(pts
				(xy -1.524508 -0.903224) (xy -1.793748 -1.711452) (xy -2.332736 -1.172718)
			)
			(stroke
				(width 0)
				(type default)
			)
			(fill yes)
			(layer "F.SilkS")
		)
		(fp_line
			(start -0.674878 -1.100074)
			(end 0.674878 -1.100074)
			(stroke
				(width 0.1)
				(type default)
			)
			(layer "F.Fab")
		)
		(fp_line
			(start -0.674878 1.100074)
			(end -0.674878 -1.100074)
			(stroke
				(width 0.1)
				(type default)
			)
			(layer "F.Fab")
		)
		(fp_line
			(start 0.674878 -1.100074)
			(end 0.674878 1.100074)
			(stroke
				(width 0.1)
				(type default)
			)
			(layer "F.Fab")
		)
		(fp_line
			(start 0.674878 1.100074)
			(end -0.674878 1.100074)
			(stroke
				(width 0.1)
				(type default)
			)
			(layer "F.Fab")
		)
		(fp_poly
			(pts
				(xy -1.4605 -0.7493) (xy -2.2225 -1.1303) (xy -2.2225 -0.3683)
			)
			(stroke
				(width 0)
				(type default)
			)
			(fill yes)
			(layer "F.Fab")
		)
		(pad "1" smd rect
			(at -0.899922 -0.750062 270)
			(size 0.6096 0.6096)
			(layers "F.Cu" "F.Mask" "F.Paste")
			(net "GND")
		)
		(pad "2" smd rect
			(at -0.899922 0 270)
			(size 0.4064 0.6096)
			(layers "F.Cu" "F.Mask" "F.Paste")
			(net "P12V_SSD5_PG_G1")
		)
		(pad "3" smd rect
			(at -0.899922 0.750062 270)
			(size 0.6096 0.6096)
			(layers "F.Cu" "F.Mask" "F.Paste")
			(net "PWRGD_P12V_SSD5_D")
		)
		(pad "4" smd rect
			(at 0.899922 0.750062 270)
			(size 0.6096 0.6096)
			(layers "F.Cu" "F.Mask" "F.Paste")
			(net "GND")
		)
		(pad "5" smd rect
			(at 0.899922 0 270)
			(size 0.4064 0.6096)
			(layers "F.Cu" "F.Mask" "F.Paste")
			(net "P12V_SSD5_PG_G2")
		)
		(pad "6" smd rect
			(at 0.899922 -0.750062 270)
			(size 0.6096 0.6096)
			(layers "F.Cu" "F.Mask" "F.Paste")
			(net "P12V_SSD5_PG_G2")
		)
	)
	(footprint ""
		(layer "F.Cu")
		(at 247.74271 -162.003994 -90)
		(property "Reference" "C843"
			(at 0 0 270)
			(layer "F.SilkS")
			(hide yes)
			(effects
				(font
					(size 1.27 1.27)
				)
			)
		)
		(property "Value" ""
			(at 0 0 270)
			(layer "F.Fab")
			(effects
				(font
					(size 1.27 1.27)
				)
			)
		)
		(duplicate_pad_numbers_are_jumpers no)
		(fp_line
			(start -0.7874 0.4064)
			(end -0.7874 -0.4064)
			(stroke
				(width 0.1524)
				(type default)
			)
			(layer "F.SilkS")
		)
		(fp_line
			(start 0.7874 0.4064)
			(end -0.7874 0.4064)
			(stroke
				(width 0.1524)
				(type default)
			)
			(layer "F.SilkS")
		)
		(fp_line
			(start -0.7874 -0.4064)
			(end 0.7874 -0.4064)
			(stroke
				(width 0.1524)
				(type default)
			)
			(layer "F.SilkS")
		)
		(fp_line
			(start 0.7874 -0.4064)
			(end 0.7874 0.4064)
			(stroke
				(width 0.1524)
				(type default)
			)
			(layer "F.SilkS")
		)
		(fp_line
			(start -0.67945 0.3048)
			(end -0.67945 -0.305054)
			(stroke
				(width 0.1)
				(type default)
			)
			(layer "F.Fab")
		)
		(fp_line
			(start -0.12065 0.3048)
			(end -0.67945 0.3048)
			(stroke
				(width 0.1)
				(type default)
			)
			(layer "F.Fab")
		)
		(fp_line
			(start 0.120396 0.3048)
			(end 0.120396 0.2794)
			(stroke
				(width 0.1)
				(type default)
			)
			(layer "F.Fab")
		)
		(fp_line
			(start 0.67945 0.3048)
			(end 0.120396 0.3048)
			(stroke
				(width 0.1)
				(type default)
			)
			(layer "F.Fab")
		)
		(fp_line
			(start -0.12065 0.2794)
			(end -0.12065 0.3048)
			(stroke
				(width 0.1)
				(type default)
			)
			(layer "F.Fab")
		)
		(fp_line
			(start 0.120396 0.2794)
			(end -0.12065 0.2794)
			(stroke
				(width 0.1)
				(type default)
			)
			(layer "F.Fab")
		)
		(fp_line
			(start -0.12065 -0.2794)
			(end 0.12065 -0.2794)
			(stroke
				(width 0.1)
				(type default)
			)
			(layer "F.Fab")
		)
		(fp_line
			(start 0.12065 -0.2794)
			(end 0.12065 -0.3048)
			(stroke
				(width 0.1)
				(type default)
			)
			(layer "F.Fab")
		)
		(fp_line
			(start 0.12065 -0.3048)
			(end 0.67945 -0.3048)
			(stroke
				(width 0.1)
				(type default)
			)
			(layer "F.Fab")
		)
		(fp_line
			(start 0.67945 -0.3048)
			(end 0.67945 0.3048)
			(stroke
				(width 0.1)
				(type default)
			)
			(layer "F.Fab")
		)
		(fp_line
			(start -0.67945 -0.305054)
			(end -0.12065 -0.305054)
			(stroke
				(width 0.1)
				(type default)
			)
			(layer "F.Fab")
		)
		(fp_line
			(start -0.12065 -0.305054)
			(end -0.12065 -0.2794)
			(stroke
				(width 0.1)
				(type default)
			)
			(layer "F.Fab")
		)
		(pad "1" smd circle
			(at -0.40005 0 270)
			(size 0 0)
			(layers "F.Cu" "F.Mask" "F.Paste")
			(net "GND")
		)
		(pad "2" smd circle
			(at 0.40005 0 270)
			(size 0 0)
			(layers "F.Cu" "F.Mask" "F.Paste")
			(net "P12V_NIC4_CO_EN")
		)
	)
	(footprint ""
		(layer "F.Cu")
		(at 354.419154 -59.574684 90)
		(property "Reference" "PC576"
			(at 0 0 90)
			(layer "F.SilkS")
			(hide yes)
			(effects
				(font
					(size 1.27 1.27)
				)
			)
		)
		(property "Value" ""
			(at 0 0 90)
			(layer "F.Fab")
			(effects
				(font
					(size 1.27 1.27)
				)
			)
		)
		(duplicate_pad_numbers_are_jumpers no)
		(fp_line
			(start 0.7874 -0.4064)
			(end 0.7874 0.4064)
			(stroke
				(width 0.1524)
				(type default)
			)
			(layer "F.SilkS")
		)
		(fp_line
			(start -0.7874 -0.4064)
			(end 0.7874 -0.4064)
			(stroke
				(width 0.1524)
				(type default)
			)
			(layer "F.SilkS")
		)
		(fp_line
			(start 0.7874 0.4064)
			(end -0.7874 0.4064)
			(stroke
				(width 0.1524)
				(type default)
			)
			(layer "F.SilkS")
		)
		(fp_line
			(start -0.7874 0.4064)
			(end -0.7874 -0.4064)
			(stroke
				(width 0.1524)
				(type default)
			)
			(layer "F.SilkS")
		)
		(fp_line
			(start -0.12065 -0.305054)
			(end -0.12065 -0.2794)
			(stroke
				(width 0.1)
				(type default)
			)
			(layer "F.Fab")
		)
		(fp_line
			(start -0.67945 -0.305054)
			(end -0.12065 -0.305054)
			(stroke
				(width 0.1)
				(type default)
			)
			(layer "F.Fab")
		)
		(fp_line
			(start 0.67945 -0.3048)
			(end 0.67945 0.3048)
			(stroke
				(width 0.1)
				(type default)
			)
			(layer "F.Fab")
		)
		(fp_line
			(start 0.12065 -0.3048)
			(end 0.67945 -0.3048)
			(stroke
				(width 0.1)
				(type default)
			)
			(layer "F.Fab")
		)
		(fp_line
			(start 0.12065 -0.2794)
			(end 0.12065 -0.3048)
			(stroke
				(width 0.1)
				(type default)
			)
			(layer "F.Fab")
		)
		(fp_line
			(start -0.12065 -0.2794)
			(end 0.12065 -0.2794)
			(stroke
				(width 0.1)
				(type default)
			)
			(layer "F.Fab")
		)
		(fp_line
			(start 0.120396 0.2794)
			(end -0.12065 0.2794)
			(stroke
				(width 0.1)
				(type default)
			)
			(layer "F.Fab")
		)
		(fp_line
			(start -0.12065 0.2794)
			(end -0.12065 0.3048)
			(stroke
				(width 0.1)
				(type default)
			)
			(layer "F.Fab")
		)
		(fp_line
			(start 0.67945 0.3048)
			(end 0.120396 0.3048)
			(stroke
				(width 0.1)
				(type default)
			)
			(layer "F.Fab")
		)
		(fp_line
			(start 0.120396 0.3048)
			(end 0.120396 0.2794)
			(stroke
				(width 0.1)
				(type default)
			)
			(layer "F.Fab")
		)
		(fp_line
			(start -0.12065 0.3048)
			(end -0.67945 0.3048)
			(stroke
				(width 0.1)
				(type default)
			)
			(layer "F.Fab")
		)
		(fp_line
			(start -0.67945 0.3048)
			(end -0.67945 -0.305054)
			(stroke
				(width 0.1)
				(type default)
			)
			(layer "F.Fab")
		)
		(pad "1" smd circle
			(at -0.40005 0 90)
			(size 0 0)
			(layers "F.Cu" "F.Mask" "F.Paste")
			(net "P5V_AUX")
		)
		(pad "2" smd circle
			(at 0.40005 0 90)
			(size 0 0)
			(layers "F.Cu" "F.Mask" "F.Paste")
			(net "GND")
		)
	)
	(footprint ""
		(layer "F.Cu")
		(at 350.647 -150.368 90)
		(property "Reference" "C3603"
			(at 0 0 90)
			(layer "F.SilkS")
			(hide yes)
			(effects
				(font
					(size 1.27 1.27)
				)
			)
		)
		(property "Value" ""
			(at 0 0 90)
			(layer "F.Fab")
			(effects
				(font
					(size 1.27 1.27)
				)
			)
		)
		(duplicate_pad_numbers_are_jumpers no)
		(fp_line
			(start 0.7874 -0.4064)
			(end 0.7874 0.4064)
			(stroke
				(width 0.1524)
				(type default)
			)
			(layer "F.SilkS")
		)
		(fp_line
			(start -0.7874 -0.4064)
			(end 0.7874 -0.4064)
			(stroke
				(width 0.1524)
				(type default)
			)
			(layer "F.SilkS")
		)
		(fp_line
			(start 0.7874 0.4064)
			(end -0.7874 0.4064)
			(stroke
				(width 0.1524)
				(type default)
			)
			(layer "F.SilkS")
		)
		(fp_line
			(start -0.7874 0.4064)
			(end -0.7874 -0.4064)
			(stroke
				(width 0.1524)
				(type default)
			)
			(layer "F.SilkS")
		)
		(fp_line
			(start -0.12065 -0.305054)
			(end -0.12065 -0.2794)
			(stroke
				(width 0.1)
				(type default)
			)
			(layer "F.Fab")
		)
		(fp_line
			(start -0.67945 -0.305054)
			(end -0.12065 -0.305054)
			(stroke
				(width 0.1)
				(type default)
			)
			(layer "F.Fab")
		)
		(fp_line
			(start 0.67945 -0.3048)
			(end 0.67945 0.3048)
			(stroke
				(width 0.1)
				(type default)
			)
			(layer "F.Fab")
		)
		(fp_line
			(start 0.12065 -0.3048)
			(end 0.67945 -0.3048)
			(stroke
				(width 0.1)
				(type default)
			)
			(layer "F.Fab")
		)
		(fp_line
			(start 0.12065 -0.2794)
			(end 0.12065 -0.3048)
			(stroke
				(width 0.1)
				(type default)
			)
			(layer "F.Fab")
		)
		(fp_line
			(start -0.12065 -0.2794)
			(end 0.12065 -0.2794)
			(stroke
				(width 0.1)
				(type default)
			)
			(layer "F.Fab")
		)
		(fp_line
			(start 0.120396 0.2794)
			(end -0.12065 0.2794)
			(stroke
				(width 0.1)
				(type default)
			)
			(layer "F.Fab")
		)
		(fp_line
			(start -0.12065 0.2794)
			(end -0.12065 0.3048)
			(stroke
				(width 0.1)
				(type default)
			)
			(layer "F.Fab")
		)
		(fp_line
			(start 0.67945 0.3048)
			(end 0.120396 0.3048)
			(stroke
				(width 0.1)
				(type default)
			)
			(layer "F.Fab")
		)
		(fp_line
			(start 0.120396 0.3048)
			(end 0.120396 0.2794)
			(stroke
				(width 0.1)
				(type default)
			)
			(layer "F.Fab")
		)
		(fp_line
			(start -0.12065 0.3048)
			(end -0.67945 0.3048)
			(stroke
				(width 0.1)
				(type default)
			)
			(layer "F.Fab")
		)
		(fp_line
			(start -0.67945 0.3048)
			(end -0.67945 -0.305054)
			(stroke
				(width 0.1)
				(type default)
			)
			(layer "F.Fab")
		)
		(pad "1" smd circle
			(at -0.40005 0 90)
			(size 0 0)
			(layers "F.Cu" "F.Mask" "F.Paste")
			(net "P3V3_AUX")
		)
		(pad "2" smd circle
			(at 0.40005 0 90)
			(size 0 0)
			(layers "F.Cu" "F.Mask" "F.Paste")
			(net "GND")
		)
	)
)
